# S9S_MB_2U (Grand Teton) — schematic netlist excerpt (pin names and nets, part order shuffled) for the footprints in the layout excerpt that follows; sources: Cadence DE-HDL packaged netlist, KiCad conversion of 03242023_DA0F0TMBIJ0_F0T_Motherboard_J_brd_V01_OCP.brd

C1339  Q_CAP  100NF 50V 10% X7R  pkg C0402  page 260 : A = P3V3 ; B = GND
R487  Q_RES  1K 1% CHIP  pkg 0402LF  page 190 : A = P3V3_AUX ; B = M2_SSD0_CLKREQ_EN_N_BUF

(kicad_pcb
	(version 20260206)
	(generator "pcbnew")
	(generator_version "10.0")
	(general
		(thickness 1.6)
		(legacy_teardrops no)
	)
	(paper "A4")
	(title_block
		(title "03242023_DA0F0TMBIJ0_F0T_Motherboard_J_brd_V01_OCP.brd")
		(comment 1 "Grand Teton / footprints 3807-3808 of 6105")
	)
	(layers
		(0 "F.Cu" signal "TOP")
		(4 "In1.Cu" signal "GND")
		(6 "In2.Cu" signal "IN1")
		(8 "In3.Cu" signal "GND1")
		(10 "In4.Cu" signal "IN2")
		(12 "In5.Cu" signal "GND2")
		(14 "In6.Cu" signal "IN3")
		(16 "In7.Cu" signal "GND3")
		(18 "In8.Cu" signal "VCC")
		(20 "In9.Cu" signal "VCC1")
		(22 "In10.Cu" signal "GND4")
		(24 "In11.Cu" signal "IN4")
		(26 "In12.Cu" signal "GND5")
		(28 "In13.Cu" signal "IN5")
		(30 "In14.Cu" signal "GND6")
		(32 "In15.Cu" signal "IN6")
		(34 "In16.Cu" signal "GND7")
		(2 "B.Cu" signal "BOTTOM")
		(9 "F.Adhes" user "F.Adhesive")
		(11 "B.Adhes" user "B.Adhesive")
		(13 "F.Paste" user "Package Geometry/Pastemask Top")
		(15 "B.Paste" user "Package Geometry/Pastemask Bottom")
		(5 "F.SilkS" user "Ref Des/Silkscreen Top")
		(7 "B.SilkS" user "Ref Des/Silkscreen Bottom")
		(1 "F.Mask" user "Board Geometry/Soldermask Top")
		(3 "B.Mask" user "Board Geometry/Soldermask Bottom")
		(17 "Dwgs.User" user "User.Drawings")
		(19 "Cmts.User" user "User.Comments")
		(21 "Eco1.User" user "User.Eco1")
		(23 "Eco2.User" user "User.Eco2")
		(25 "Edge.Cuts" user "Board Geometry/Outline")
		(27 "Margin" user)
		(31 "F.CrtYd" user "Package Geometry/Place Bound Top")
		(29 "B.CrtYd" user "Package Geometry/Place Bound Bottom")
		(35 "F.Fab" user "Ref Des/Assembly Top")
		(33 "B.Fab" user "Ref Des/Assembly Bottom")
	)
	(footprint ""
		(layer "F.Cu")
		(at 164.52088 -43.525948)
		(property "Reference" "R487"
			(at 0 0 0)
			(layer "F.SilkS")
			(hide yes)
			(effects
				(font
					(size 1.27 1.27)
				)
			)
		)
		(property "Value" ""
			(at 0 0 0)
			(layer "F.Fab")
			(effects
				(font
					(size 1.27 1.27)
				)
			)
		)
		(duplicate_pad_numbers_are_jumpers no)
		(fp_line
			(start -0.7874 -0.4064)
			(end 0.7874 -0.4064)
			(stroke
				(width 0.1524)
				(type default)
			)
			(layer "F.SilkS")
		)
		(fp_line
			(start -0.7874 0.4064)
			(end -0.7874 -0.4064)
			(stroke
				(width 0.1524)
				(type default)
			)
			(layer "F.SilkS")
		)
		(fp_line
			(start 0.7874 -0.4064)
			(end 0.7874 0.4064)
			(stroke
				(width 0.1524)
				(type default)
			)
			(layer "F.SilkS")
		)
		(fp_line
			(start 0.7874 0.4064)
			(end -0.7874 0.4064)
			(stroke
				(width 0.1524)
				(type default)
			)
			(layer "F.SilkS")
		)
		(fp_line
			(start -0.67945 -0.305054)
			(end -0.12065 -0.305054)
			(stroke
				(width 0.1)
				(type default)
			)
			(layer "F.Fab")
		)
		(fp_line
			(start -0.67945 0.3048)
			(end -0.67945 -0.305054)
			(stroke
				(width 0.1)
				(type default)
			)
			(layer "F.Fab")
		)
		(fp_line
			(start -0.12065 -0.305054)
			(end -0.12065 -0.2794)
			(stroke
				(width 0.1)
				(type default)
			)
			(layer "F.Fab")
		)
		(fp_line
			(start -0.12065 -0.2794)
			(end 0.12065 -0.2794)
			(stroke
				(width 0.1)
				(type default)
			)
			(layer "F.Fab")
		)
		(fp_line
			(start -0.12065 0.2794)
			(end -0.12065 0.3048)
			(stroke
				(width 0.1)
				(type default)
			)
			(layer "F.Fab")
		)
		(fp_line
			(start -0.12065 0.3048)
			(end -0.67945 0.3048)
			(stroke
				(width 0.1)
				(type default)
			)
			(layer "F.Fab")
		)
		(fp_line
			(start 0.120396 0.2794)
			(end -0.12065 0.2794)
			(stroke
				(width 0.1)
				(type default)
			)
			(layer "F.Fab")
		)
		(fp_line
			(start 0.120396 0.3048)
			(end 0.120396 0.2794)
			(stroke
				(width 0.1)
				(type default)
			)
			(layer "F.Fab")
		)
		(fp_line
			(start 0.12065 -0.3048)
			(end 0.67945 -0.3048)
			(stroke
				(width 0.1)
				(type default)
			)
			(layer "F.Fab")
		)
		(fp_line
			(start 0.12065 -0.2794)
			(end 0.12065 -0.3048)
			(stroke
				(width 0.1)
				(type default)
			)
			(layer "F.Fab")
		)
		(fp_line
			(start 0.67945 -0.3048)
			(end 0.67945 0.3048)
			(stroke
				(width 0.1)
				(type default)
			)
			(layer "F.Fab")
		)
		(fp_line
			(start 0.67945 0.3048)
			(end 0.120396 0.3048)
			(stroke
				(width 0.1)
				(type default)
			)
			(layer "F.Fab")
		)
		(pad "1" smd circle
			(at -0.40005 0)
			(size 0 0)
			(layers "F.Cu" "F.Mask" "F.Paste")
			(net "P3V3_AUX")
		)
		(pad "2" smd circle
			(at 0.40005 0)
			(size 0 0)
			(layers "F.Cu" "F.Mask" "F.Paste")
			(net "M2_SSD0_CLKREQ_EN_N_BUF")
		)
	)
	(footprint ""
		(layer "F.Cu")
		(at 432.798728 -57.916826 90)
		(property "Reference" "C1339"
			(at 0 0 90)
			(layer "F.SilkS")
			(hide yes)
			(effects
				(font
					(size 1.27 1.27)
				)
			)
		)
		(property "Value" ""
			(at 0 0 90)
			(layer "F.Fab")
			(effects
				(font
					(size 1.27 1.27)
				)
			)
		)
		(duplicate_pad_numbers_are_jumpers no)
		(fp_line
			(start 0.7874 -0.4064)
			(end 0.7874 0.4064)
			(stroke
				(width 0.1524)
				(type default)
			)
			(layer "F.SilkS")
		)
		(fp_line
			(start -0.7874 -0.4064)
			(end 0.7874 -0.4064)
			(stroke
				(width 0.1524)
				(type default)
			)
			(layer "F.SilkS")
		)
		(fp_line
			(start 0.7874 0.4064)
			(end -0.7874 0.4064)
			(stroke
				(width 0.1524)
				(type default)
			)
			(layer "F.SilkS")
		)
		(fp_line
			(start -0.7874 0.4064)
			(end -0.7874 -0.4064)
			(stroke
				(width 0.1524)
				(type default)
			)
			(layer "F.SilkS")
		)
		(fp_line
			(start -0.12065 -0.305054)
			(end -0.12065 -0.2794)
			(stroke
				(width 0.1)
				(type default)
			)
			(layer "F.Fab")
		)
		(fp_line
			(start -0.67945 -0.305054)
			(end -0.12065 -0.305054)
			(stroke
				(width 0.1)
				(type default)
			)
			(layer "F.Fab")
		)
		(fp_line
			(start 0.67945 -0.3048)
			(end 0.67945 0.3048)
			(stroke
				(width 0.1)
				(type default)
			)
			(layer "F.Fab")
		)
		(fp_line
			(start 0.12065 -0.3048)
			(end 0.67945 -0.3048)
			(stroke
				(width 0.1)
				(type default)
			)
			(layer "F.Fab")
		)
		(fp_line
			(start 0.12065 -0.2794)
			(end 0.12065 -0.3048)
			(stroke
				(width 0.1)
				(type default)
			)
			(layer "F.Fab")
		)
		(fp_line
			(start -0.12065 -0.2794)
			(end 0.12065 -0.2794)
			(stroke
				(width 0.1)
				(type default)
			)
			(layer "F.Fab")
		)
		(fp_line
			(start 0.120396 0.2794)
			(end -0.12065 0.2794)
			(stroke
				(width 0.1)
				(type default)
			)
			(layer "F.Fab")
		)
		(fp_line
			(start -0.12065 0.2794)
			(end -0.12065 0.3048)
			(stroke
				(width 0.1)
				(type default)
			)
			(layer "F.Fab")
		)
		(fp_line
			(start 0.67945 0.3048)
			(end 0.120396 0.3048)
			(stroke
				(width 0.1)
				(type default)
			)
			(layer "F.Fab")
		)
		(fp_line
			(start 0.120396 0.3048)
			(end 0.120396 0.2794)
			(stroke
				(width 0.1)
				(type default)
			)
			(layer "F.Fab")
		)
		(fp_line
			(start -0.12065 0.3048)
			(end -0.67945 0.3048)
			(stroke
				(width 0.1)
				(type default)
			)
			(layer "F.Fab")
		)
		(fp_line
			(start -0.67945 0.3048)
			(end -0.67945 -0.305054)
			(stroke
				(width 0.1)
				(type default)
			)
			(layer "F.Fab")
		)
		(pad "1" smd circle
			(at -0.40005 0 90)
			(size 0 0)
			(layers "F.Cu" "F.Mask" "F.Paste")
			(net "P3V3")
		)
		(pad "2" smd circle
			(at 0.40005 0 90)
			(size 0 0)
			(layers "F.Cu" "F.Mask" "F.Paste")
			(net "GND")
		)
	)
)
